(kicad_pcb
	(version 20260206)
	(generator "pcbnew")
	(generator_version "10.0")
	(general
		(thickness 1.6)
		(legacy_teardrops no)
	)
	(paper "A4")
	(title_block
		(title "v1-chassis-manager — T6M_CM_d_v01_1031_1645.brd")
		(comment 1 "Open CloudServer (Microsoft) / footprint 1507 of 2512 (U2), pads 362-482 of 1283")
	)
	(layers
		(0 "F.Cu" signal "TOP")
		(4 "In1.Cu" signal "GND1")
		(6 "In2.Cu" signal "IN1")
		(8 "In3.Cu" signal "VCC1")
		(10 "In4.Cu" signal "VCC2")
		(12 "In5.Cu" signal "GND2")
		(14 "In6.Cu" signal "IN2")
		(16 "In7.Cu" signal "IN3")
		(18 "In8.Cu" signal "GND3")
		(2 "B.Cu" signal "BOTTOM")
		(9 "F.Adhes" user "F.Adhesive")
		(11 "B.Adhes" user "B.Adhesive")
		(13 "F.Paste" user "Package Geometry/Pastemask Top")
		(15 "B.Paste" user "Package Geometry/Pastemask Bottom")
		(5 "F.SilkS" user "Ref Des/Silkscreen Top")
		(7 "B.SilkS" user "Ref Des/Silkscreen Bottom")
		(1 "F.Mask" user "Board Geometry/Soldermask Top")
		(3 "B.Mask" user "Board Geometry/Soldermask Bottom")
		(17 "Dwgs.User" user "User.Drawings")
		(19 "Cmts.User" user "User.Comments")
		(21 "Eco1.User" user "User.Eco1")
		(23 "Eco2.User" user "User.Eco2")
		(25 "Edge.Cuts" user "Board Geometry/Outline")
		(27 "Margin" user)
		(31 "F.CrtYd" user "Package Geometry/Place Bound Top")
		(29 "B.CrtYd" user "Package Geometry/Place Bound Bottom")
		(35 "F.Fab" user "Ref Des/Assembly Top")
		(33 "B.Fab" user "Ref Des/Assembly Bottom")
	)
	(footprint ""
		(layer "F.Cu")
		(at 58.000646 -75.799442)
		(property "Reference" "U2"
			(at -20.2438 -18.364708 0)
			(unlocked yes)
			(layer "F.SilkS")
			(effects
				(font
					(size 1.6002 1.1938)
					(thickness 0.1524)
				)
				(justify left)
			)
		)
		(property "Value" ""
			(at 0 0 0)
			(layer "F.Fab")
			(effects
				(font
					(size 1.27 1.27)
				)
			)
		)
		(duplicate_pad_numbers_are_jumpers no)
		(pad "AR19" smd circle
			(at -7.248398 3.742436)
			(size 0.3048 0.3048)
			(layers "F.Cu" "F.Mask" "F.Paste")
			(net "P1V05_NODE1")
		)
		(pad "AR48" smd circle
			(at 7.248398 3.50266)
			(size 0.3048 0.3048)
			(layers "F.Cu" "F.Mask" "F.Paste")
			(net "P1V05_NODE1")
		)
		(pad "AR50" smd circle
			(at 8.010398 3.50266)
			(size 0.3048 0.3048)
			(layers "F.Cu" "F.Mask" "F.Paste")
			(net "P1V05_NODE1")
		)
		(pad "AR51" smd circle
			(at 8.772398 3.50266)
			(size 0.3048 0.3048)
			(layers "F.Cu" "F.Mask" "F.Paste")
			(net "GND")
		)
		(pad "AR53" smd circle
			(at 9.534398 3.50266)
			(size 0.3048 0.3048)
			(layers "F.Cu" "F.Mask" "F.Paste")
			(net "XDP_CPU_NODE1_VISA1")
		)
		(pad "AR54" smd circle
			(at 10.296398 3.50266)
			(size 0.3048 0.3048)
			(layers "F.Cu" "F.Mask" "F.Paste")
			(net "XDP_CPU_NODE1_VISA4")
		)
		(pad "AR56" smd circle
			(at 11.058398 3.50266)
			(size 0.3048 0.3048)
			(layers "F.Cu" "F.Mask" "F.Paste")
			(net "GND")
		)
		(pad "AR57" smd circle
			(at 11.820398 3.50266)
			(size 0.3048 0.3048)
			(layers "F.Cu" "F.Mask" "F.Paste")
			(net "XDP_CPU_NODE1_VISA7")
		)
		(pad "AR59" smd circle
			(at 12.582398 3.50266)
			(size 0.3048 0.3048)
			(layers "F.Cu" "F.Mask" "F.Paste")
			(net "XDP_CPU_NODE1_VISA11")
		)
		(pad "AR60" smd circle
			(at 13.344398 3.50266)
			(size 0.3048 0.3048)
			(layers "F.Cu" "F.Mask" "F.Paste")
			(net "XDP_CPU_NODE1_VISA8")
		)
		(pad "AR62" smd circle
			(at 14.063218 3.888486)
			(size 0.3048 0.3048)
			(layers "F.Cu" "F.Mask" "F.Paste")
			(net "GND")
		)
		(pad "AR63" smd circle
			(at 14.751558 3.719576)
			(size 0.3048 0.3048)
			(layers "F.Cu" "F.Mask" "F.Paste")
			(net "M1_DQ_NODE1_DQ61")
		)
		(pad "AR65" smd circle
			(at 15.805658 3.63982)
			(size 0.3048 0.3048)
			(layers "F.Cu" "F.Mask" "F.Paste")
			(net "M1_DQ_NODE1_DQ58")
		)
		(pad "AT5" smd circle
			(at -14.063218 4.09575)
			(size 0.3048 0.3048)
			(layers "F.Cu" "F.Mask" "F.Paste")
			(net "PD_CPU_NODE1_RP1_PERN")
		)
		(pad "AT7" smd circle
			(at -13.344398 4.44246)
			(size 0.3048 0.3048)
			(layers "F.Cu" "F.Mask" "F.Paste")
			(net "GND")
		)
		(pad "AT8" smd circle
			(at -12.582398 4.44246)
			(size 0.3048 0.3048)
			(layers "F.Cu" "F.Mask" "F.Paste")
			(net "Net_387")
		)
		(pad "AT10" smd circle
			(at -11.820398 4.44246)
			(size 0.3048 0.3048)
			(layers "F.Cu" "F.Mask" "F.Paste")
			(net "Net_377")
		)
		(pad "AT11" smd circle
			(at -11.058398 4.44246)
			(size 0.3048 0.3048)
			(layers "F.Cu" "F.Mask" "F.Paste")
			(net "GND")
		)
		(pad "AT13" smd circle
			(at -10.296398 4.44246)
			(size 0.3048 0.3048)
			(layers "F.Cu" "F.Mask" "F.Paste")
			(net "Net_395")
		)
		(pad "AT14" smd circle
			(at -9.534398 4.44246)
			(size 0.3048 0.3048)
			(layers "F.Cu" "F.Mask" "F.Paste")
			(net "Net_450")
		)
		(pad "AT16" smd circle
			(at -8.772398 4.44246)
			(size 0.3048 0.3048)
			(layers "F.Cu" "F.Mask" "F.Paste")
			(net "GND")
		)
		(pad "AT17" smd circle
			(at -8.010398 4.44246)
			(size 0.3048 0.3048)
			(layers "F.Cu" "F.Mask" "F.Paste")
			(net "GND")
		)
		(pad "AT19" smd circle
			(at -7.248398 4.44246)
			(size 0.3048 0.3048)
			(layers "F.Cu" "F.Mask" "F.Paste")
			(net "GND")
		)
		(pad "AT21" smd circle
			(at -6.00075 4.0005)
			(size 0.381 0.381)
			(layers "F.Cu" "F.Mask" "F.Paste")
			(net "P1V5_NODE1")
		)
		(pad "AT23" smd circle
			(at -5.20065 4.0005)
			(size 0.381 0.381)
			(layers "F.Cu" "F.Mask" "F.Paste")
			(net "A_NODE1_RP0_RCOMP")
		)
		(pad "AT25" smd circle
			(at -4.40055 4.0005)
			(size 0.381 0.381)
			(layers "F.Cu" "F.Mask" "F.Paste")
			(net "GND")
		)
		(pad "AT26" smd circle
			(at -3.60045 4.0005)
			(size 0.381 0.381)
			(layers "F.Cu" "F.Mask" "F.Paste")
			(net "GND")
		)
		(pad "AT28" smd circle
			(at -2.80035 4.0005)
			(size 0.381 0.381)
			(layers "F.Cu" "F.Mask" "F.Paste")
			(net "P1V5_NODE1")
		)
		(pad "AT29" smd circle
			(at -2.00025 4.0005)
			(size 0.381 0.381)
			(layers "F.Cu" "F.Mask" "F.Paste")
			(net "GND")
		)
		(pad "AT31" smd circle
			(at -1.20015 4.0005)
			(size 0.381 0.381)
			(layers "F.Cu" "F.Mask" "F.Paste")
			(net "P1V05_NODE1")
		)
		(pad "AT32" smd circle
			(at -0.40005 4.0005)
			(size 0.381 0.381)
			(layers "F.Cu" "F.Mask" "F.Paste")
			(net "GND")
		)
		(pad "AT34" smd circle
			(at 0.40005 4.0005)
			(size 0.381 0.381)
			(layers "F.Cu" "F.Mask" "F.Paste")
			(net "P1V05_NODE1")
		)
		(pad "AT36" smd circle
			(at 1.20015 4.0005)
			(size 0.381 0.381)
			(layers "F.Cu" "F.Mask" "F.Paste")
			(net "GND")
		)
		(pad "AT38" smd circle
			(at 2.00025 4.0005)
			(size 0.381 0.381)
			(layers "F.Cu" "F.Mask" "F.Paste")
			(net "GND")
		)
		(pad "AT39" smd circle
			(at 2.80035 4.0005)
			(size 0.381 0.381)
			(layers "F.Cu" "F.Mask" "F.Paste")
			(net "GND")
		)
		(pad "AT41" smd circle
			(at 3.60045 4.0005)
			(size 0.381 0.381)
			(layers "F.Cu" "F.Mask" "F.Paste")
			(net "GND")
		)
		(pad "AT42" smd circle
			(at 4.40055 4.0005)
			(size 0.381 0.381)
			(layers "F.Cu" "F.Mask" "F.Paste")
			(net "GND")
		)
		(pad "AT44" smd circle
			(at 5.20065 4.0005)
			(size 0.381 0.381)
			(layers "F.Cu" "F.Mask" "F.Paste")
			(net "GND")
		)
		(pad "AT46" smd circle
			(at 6.00075 4.0005)
			(size 0.381 0.381)
			(layers "F.Cu" "F.Mask" "F.Paste")
			(net "GND")
		)
		(pad "AT48" smd circle
			(at 7.248398 4.202684)
			(size 0.3048 0.3048)
			(layers "F.Cu" "F.Mask" "F.Paste")
			(net "GND")
		)
		(pad "AT50" smd circle
			(at 8.010398 4.202684)
			(size 0.3048 0.3048)
			(layers "F.Cu" "F.Mask" "F.Paste")
			(net "GND")
		)
		(pad "AT51" smd circle
			(at 8.772398 4.202684)
			(size 0.3048 0.3048)
			(layers "F.Cu" "F.Mask" "F.Paste")
			(net "GND")
		)
		(pad "AT53" smd circle
			(at 9.534398 4.202684)
			(size 0.3048 0.3048)
			(layers "F.Cu" "F.Mask" "F.Paste")
			(net "XDP_CPU_NODE1_VISA0")
		)
		(pad "AT54" smd circle
			(at 10.296398 4.202684)
			(size 0.3048 0.3048)
			(layers "F.Cu" "F.Mask" "F.Paste")
			(net "XDP_CPU_NODE1_VISA3")
		)
		(pad "AT56" smd circle
			(at 11.058398 4.202684)
			(size 0.3048 0.3048)
			(layers "F.Cu" "F.Mask" "F.Paste")
			(net "GND")
		)
		(pad "AT57" smd circle
			(at 11.820398 4.202684)
			(size 0.3048 0.3048)
			(layers "F.Cu" "F.Mask" "F.Paste")
			(net "XDP_CPU_NODE1_VISA6")
		)
		(pad "AT59" smd circle
			(at 12.582398 4.202684)
			(size 0.3048 0.3048)
			(layers "F.Cu" "F.Mask" "F.Paste")
			(net "XDP_CPU_NODE1_VISA2")
		)
		(pad "AT60" smd circle
			(at 13.344398 4.202684)
			(size 0.3048 0.3048)
			(layers "F.Cu" "F.Mask" "F.Paste")
			(net "XDP_CPU_NODE1_VISA5")
		)
		(pad "AT63" smd circle
			(at 14.542516 4.39928)
			(size 0.3048 0.3048)
			(layers "F.Cu" "F.Mask" "F.Paste")
			(net "M1_DQ_NODE1_DQ56")
		)
		(pad "AT64" smd circle
			(at 15.304516 4.45008)
			(size 0.3048 0.3048)
			(layers "F.Cu" "F.Mask" "F.Paste")
			(net "M1_DQ_NODE1_DQ57")
		)
		(pad "AT66" smd oval
			(at 16.249396 4.39928 90)
			(size 0.254 0.3429)
			(layers "F.Cu" "F.Mask" "F.Paste")
			(net "GND")
		)
		(pad "AU1" smd oval
			(at -16.249396 4.606544 270)
			(size 0.254 0.3429)
			(layers "F.Cu" "F.Mask" "F.Paste")
			(net "PD_CPU_NODE1_RP1_PERN")
		)
		(pad "AU3" smd circle
			(at -15.304516 4.555744)
			(size 0.3048 0.3048)
			(layers "F.Cu" "F.Mask" "F.Paste")
			(net "PD_CPU_NODE1_RP1_PERP")
		)
		(pad "AU4" smd circle
			(at -14.542516 4.606544)
			(size 0.3048 0.3048)
			(layers "F.Cu" "F.Mask" "F.Paste")
			(net "GND")
		)
		(pad "AU21" smd circle
			(at -6.00075 4.8006)
			(size 0.381 0.381)
			(layers "F.Cu" "F.Mask" "F.Paste")
			(net "GND")
		)
		(pad "AU23" smd circle
			(at -5.20065 4.8006)
			(size 0.381 0.381)
			(layers "F.Cu" "F.Mask" "F.Paste")
			(net "P1V05_NODE1")
		)
		(pad "AU25" smd circle
			(at -4.40055 4.8006)
			(size 0.381 0.381)
			(layers "F.Cu" "F.Mask" "F.Paste")
			(net "P1V05_NODE1")
		)
		(pad "AU26" smd circle
			(at -3.60045 4.8006)
			(size 0.381 0.381)
			(layers "F.Cu" "F.Mask" "F.Paste")
			(net "P1V05_NODE1")
		)
		(pad "AU28" smd circle
			(at -2.80035 4.8006)
			(size 0.381 0.381)
			(layers "F.Cu" "F.Mask" "F.Paste")
			(net "P1V05_NODE1")
		)
		(pad "AU29" smd circle
			(at -2.00025 4.8006)
			(size 0.381 0.381)
			(layers "F.Cu" "F.Mask" "F.Paste")
			(net "P1V05_NODE1")
		)
		(pad "AU31" smd circle
			(at -1.20015 4.8006)
			(size 0.381 0.381)
			(layers "F.Cu" "F.Mask" "F.Paste")
			(net "GND")
		)
		(pad "AU32" smd circle
			(at -0.40005 4.8006)
			(size 0.381 0.381)
			(layers "F.Cu" "F.Mask" "F.Paste")
			(net "P1V05_NODE1")
		)
		(pad "AU34" smd circle
			(at 0.40005 4.8006)
			(size 0.381 0.381)
			(layers "F.Cu" "F.Mask" "F.Paste")
			(net "GND")
		)
		(pad "AU36" smd circle
			(at 1.20015 4.8006)
			(size 0.381 0.381)
			(layers "F.Cu" "F.Mask" "F.Paste")
			(net "P1V05_NODE1")
		)
		(pad "AU38" smd circle
			(at 2.00025 4.8006)
			(size 0.381 0.381)
			(layers "F.Cu" "F.Mask" "F.Paste")
			(net "P1V05_NODE1")
		)
		(pad "AU39" smd circle
			(at 2.80035 4.8006)
			(size 0.381 0.381)
			(layers "F.Cu" "F.Mask" "F.Paste")
			(net "P1V05_NODE1")
		)
		(pad "AU41" smd circle
			(at 3.60045 4.8006)
			(size 0.381 0.381)
			(layers "F.Cu" "F.Mask" "F.Paste")
			(net "P1V05_NODE1")
		)
		(pad "AU42" smd circle
			(at 4.40055 4.8006)
			(size 0.381 0.381)
			(layers "F.Cu" "F.Mask" "F.Paste")
			(net "P1V05_NODE1")
		)
		(pad "AU44" smd circle
			(at 5.20065 4.8006)
			(size 0.381 0.381)
			(layers "F.Cu" "F.Mask" "F.Paste")
			(net "P1V05_NODE1")
		)
		(pad "AU46" smd circle
			(at 6.00075 4.8006)
			(size 0.381 0.381)
			(layers "F.Cu" "F.Mask" "F.Paste")
			(net "P1V05_NODE1")
		)
		(pad "AU47" smd circle
			(at 6.726174 4.8006)
			(size 0.3048 0.3048)
			(layers "F.Cu" "F.Mask" "F.Paste")
			(net "P1V05_NODE1")
		)
		(pad "AU62" smd circle
			(at 14.063218 4.910074)
			(size 0.3048 0.3048)
			(layers "F.Cu" "F.Mask" "F.Paste")
			(net "GND")
		)
		(pad "AV2" smd circle
			(at -15.805658 5.366004)
			(size 0.3048 0.3048)
			(layers "F.Cu" "F.Mask" "F.Paste")
			(net "PD_CPU_NODE1_RP1_PERP")
		)
		(pad "AV4" smd circle
			(at -14.751558 5.286248)
			(size 0.3048 0.3048)
			(layers "F.Cu" "F.Mask" "F.Paste")
			(net "GND")
		)
		(pad "AV5" smd circle
			(at -14.063218 5.117338)
			(size 0.3048 0.3048)
			(layers "F.Cu" "F.Mask" "F.Paste")
			(net "GND")
		)
		(pad "AV63" smd circle
			(at 14.794738 5.067808)
			(size 0.3048 0.3048)
			(layers "F.Cu" "F.Mask" "F.Paste")
			(net "GND")
		)
		(pad "AV65" smd circle
			(at 15.752318 5.12064)
			(size 0.3048 0.3048)
			(layers "F.Cu" "F.Mask" "F.Paste")
			(net "GND")
		)
		(pad "AW3" smd circle
			(at -15.247112 5.789422)
			(size 0.3048 0.3048)
			(layers "F.Cu" "F.Mask" "F.Paste")
			(net "GND")
		)
		(pad "AW5" smd circle
			(at -14.013688 5.819648)
			(size 0.3048 0.3048)
			(layers "F.Cu" "F.Mask" "F.Paste")
			(net "GND")
		)
		(pad "AW8" smd circle
			(at -12.963398 5.728716)
			(size 0.3048 0.3048)
			(layers "F.Cu" "F.Mask" "F.Paste")
			(net "GND")
		)
		(pad "AW9" smd circle
			(at -12.201398 5.728716)
			(size 0.3048 0.3048)
			(layers "F.Cu" "F.Mask" "F.Paste")
			(net "TP_CPU_NODE1_RP0_PETP7")
		)
		(pad "AW11" smd circle
			(at -11.439398 5.728716)
			(size 0.3048 0.3048)
			(layers "F.Cu" "F.Mask" "F.Paste")
			(net "TP_CPU_NODE1_RP0_PETN7")
		)
		(pad "AW12" smd circle
			(at -10.677398 5.728716)
			(size 0.3048 0.3048)
			(layers "F.Cu" "F.Mask" "F.Paste")
			(net "GND")
		)
		(pad "AW14" smd circle
			(at -9.915398 5.728716)
			(size 0.3048 0.3048)
			(layers "F.Cu" "F.Mask" "F.Paste")
			(net "Net_451")
		)
		(pad "AW15" smd circle
			(at -9.153398 5.728716)
			(size 0.3048 0.3048)
			(layers "F.Cu" "F.Mask" "F.Paste")
			(net "Net_452")
		)
		(pad "AW17" smd circle
			(at -8.175244 5.772404)
			(size 0.3048 0.3048)
			(layers "F.Cu" "F.Mask" "F.Paste")
			(net "GND")
		)
		(pad "AW19" smd circle
			(at -7.47522 5.772404)
			(size 0.3048 0.3048)
			(layers "F.Cu" "F.Mask" "F.Paste")
			(net "GND")
		)
		(pad "AW20" smd circle
			(at -6.80085 5.500624)
			(size 0.3048 0.3048)
			(layers "F.Cu" "F.Mask" "F.Paste")
			(net "GND")
		)
		(pad "AW21" smd circle
			(at -5.900674 5.500624)
			(size 0.3048 0.3048)
			(layers "F.Cu" "F.Mask" "F.Paste")
			(net "P1V05_NODE1")
		)
		(pad "AW23" smd circle
			(at -5.20065 5.500624)
			(size 0.3048 0.3048)
			(layers "F.Cu" "F.Mask" "F.Paste")
			(net "P1V05_NODE1")
		)
		(pad "AW25" smd circle
			(at -4.202684 5.772404)
			(size 0.3048 0.3048)
			(layers "F.Cu" "F.Mask" "F.Paste")
			(net "GND")
		)
		(pad "AW26" smd circle
			(at -3.50266 5.772404)
			(size 0.3048 0.3048)
			(layers "F.Cu" "F.Mask" "F.Paste")
			(net "GND")
		)
		(pad "AW28" smd circle
			(at -2.80035 5.500624)
			(size 0.3048 0.3048)
			(layers "F.Cu" "F.Mask" "F.Paste")
			(net "GND")
		)
		(pad "AW30" smd circle
			(at -1.900174 5.500624)
			(size 0.3048 0.3048)
			(layers "F.Cu" "F.Mask" "F.Paste")
			(net "GND")
		)
		(pad "AW31" smd circle
			(at -1.20015 5.500624)
			(size 0.3048 0.3048)
			(layers "F.Cu" "F.Mask" "F.Paste")
			(net "GND")
		)
		(pad "AW32" smd circle
			(at -0.230124 5.772404)
			(size 0.3048 0.3048)
			(layers "F.Cu" "F.Mask" "F.Paste")
			(net "P1V05_VCCACLK_DDR3_NODE1")
		)
		(pad "AW34" smd circle
			(at 0.4699 5.772404)
			(size 0.3048 0.3048)
			(layers "F.Cu" "F.Mask" "F.Paste")
			(net "GND")
		)
		(pad "AW36" smd circle
			(at 1.20015 5.500624)
			(size 0.3048 0.3048)
			(layers "F.Cu" "F.Mask" "F.Paste")
			(net "GND")
		)
		(pad "AW38" smd circle
			(at 2.100326 5.500624)
			(size 0.3048 0.3048)
			(layers "F.Cu" "F.Mask" "F.Paste")
			(net "GND")
		)
		(pad "AW39" smd circle
			(at 2.80035 5.500624)
			(size 0.3048 0.3048)
			(layers "F.Cu" "F.Mask" "F.Paste")
			(net "GND")
		)
		(pad "AW41" smd circle
			(at 3.742436 5.772404)
			(size 0.3048 0.3048)
			(layers "F.Cu" "F.Mask" "F.Paste")
			(net "GND")
		)
		(pad "AW42" smd circle
			(at 4.44246 5.772404)
			(size 0.3048 0.3048)
			(layers "F.Cu" "F.Mask" "F.Paste")
			(net "GND")
		)
		(pad "AW44" smd circle
			(at 5.20065 5.500624)
			(size 0.3048 0.3048)
			(layers "F.Cu" "F.Mask" "F.Paste")
			(net "GND")
		)
		(pad "AW46" smd circle
			(at 6.00075 5.500624)
			(size 0.3048 0.3048)
			(layers "F.Cu" "F.Mask" "F.Paste")
			(net "P1V05_NODE1")
		)
		(pad "AW47" smd circle
			(at 6.700774 5.500624)
			(size 0.3048 0.3048)
			(layers "F.Cu" "F.Mask" "F.Paste")
			(net "P1V05_NODE1")
		)
		(pad "AW49" smd circle
			(at 7.714996 5.772404)
			(size 0.3048 0.3048)
			(layers "F.Cu" "F.Mask" "F.Paste")
			(net "GND")
		)
		(pad "AW50" smd circle
			(at 8.41502 5.772404)
			(size 0.3048 0.3048)
			(layers "F.Cu" "F.Mask" "F.Paste")
			(net "GND")
		)
		(pad "AW52" smd circle
			(at 9.153398 5.48894)
			(size 0.3048 0.3048)
			(layers "F.Cu" "F.Mask" "F.Paste")
			(net "GND")
		)
		(pad "AW53" smd circle
			(at 9.915398 5.48894)
			(size 0.3048 0.3048)
			(layers "F.Cu" "F.Mask" "F.Paste")
			(net "GND")
		)
		(pad "AW55" smd circle
			(at 10.677398 5.48894)
			(size 0.3048 0.3048)
			(layers "F.Cu" "F.Mask" "F.Paste")
			(net "GND")
		)
		(pad "AW56" smd circle
			(at 11.439398 5.48894)
			(size 0.3048 0.3048)
			(layers "F.Cu" "F.Mask" "F.Paste")
			(net "XDP_CPU_NODE1_VISA14")
		)
		(pad "AW58" smd circle
			(at 12.201398 5.48894)
			(size 0.3048 0.3048)
			(layers "F.Cu" "F.Mask" "F.Paste")
			(net "XDP_CPU_NODE1_VISA17")
		)
		(pad "AW59" smd circle
			(at 12.963398 5.48894)
			(size 0.3048 0.3048)
			(layers "F.Cu" "F.Mask" "F.Paste")
			(net "GND")
		)
		(pad "AW62" smd circle
			(at 14.08049 5.617464)
			(size 0.3048 0.3048)
			(layers "F.Cu" "F.Mask" "F.Paste")
			(net "M1_DQ_NODE1_DQ51")
		)
		(pad "AW64" smd circle
			(at 15.242794 5.607558)
			(size 0.3048 0.3048)
			(layers "F.Cu" "F.Mask" "F.Paste")
			(net "M1_DQ_NODE1_DQ53")
		)
		(pad "AW66" smd oval
			(at 16.249396 5.837936 90)
			(size 0.254 0.3429)
			(layers "F.Cu" "F.Mask" "F.Paste")
			(net "GND")
		)
		(pad "AY1" smd oval
			(at -16.249396 6.0452 270)
			(size 0.254 0.3429)
			(layers "F.Cu" "F.Mask" "F.Paste")
			(net "GND")
		)
		(pad "AY2" smd circle
			(at -15.640812 6.394704)
			(size 0.3048 0.3048)
			(layers "F.Cu" "F.Mask" "F.Paste")
			(net "TP_CPU_NODE1_RP0_PERP7")
		)
		(pad "AY4" smd circle
			(at -14.90091 6.4008)
			(size 0.3048 0.3048)
			(layers "F.Cu" "F.Mask" "F.Paste")
			(net "TP_CPU_NODE1_RP0_PERN7")
		)
		(pad "AY5" smd circle
			(at -14.204442 6.497828)
			(size 0.3048 0.3048)
			(layers "F.Cu" "F.Mask" "F.Paste")
			(net "P2E_CPU_PCIE_SW_NODE1_RX_DN")
		)
		(pad "AY8" smd circle
			(at -12.963398 6.42874)
			(size 0.3048 0.3048)
			(layers "F.Cu" "F.Mask" "F.Paste")
			(net "GND")
		)
	)
)
